(kicad_pcb
	(version 20260206)
	(generator "pcbnew")
	(generator_version "10.0")
	(general
		(thickness 1.6)
		(legacy_teardrops no)
	)
	(paper "A4")
	(title_block
		(title "04192023_DAF0TMB3IC0_F0TG_MB_C_brd_V02_OCP.brd")
		(comment 1 "Grand Teton / footprints 6246-6251 of 8354")
	)
	(layers
		(0 "F.Cu" signal "TOP")
		(4 "In1.Cu" signal "GND")
		(6 "In2.Cu" signal "IN1")
		(8 "In3.Cu" signal "GND1")
		(10 "In4.Cu" signal "IN2")
		(12 "In5.Cu" signal "GND2")
		(14 "In6.Cu" signal "IN3")
		(16 "In7.Cu" signal "GND3")
		(18 "In8.Cu" signal "VCC")
		(20 "In9.Cu" signal "VCC1")
		(22 "In10.Cu" signal "GND4")
		(24 "In11.Cu" signal "IN4")
		(26 "In12.Cu" signal "GND5")
		(28 "In13.Cu" signal "IN5")
		(30 "In14.Cu" signal "GND6")
		(32 "In15.Cu" signal "IN6")
		(34 "In16.Cu" signal "GND7")
		(2 "B.Cu" signal "BOTTOM")
		(9 "F.Adhes" user "F.Adhesive")
		(11 "B.Adhes" user "B.Adhesive")
		(13 "F.Paste" user "Package Geometry/Pastemask Top")
		(15 "B.Paste" user "Package Geometry/Pastemask Bottom")
		(5 "F.SilkS" user "Ref Des/Silkscreen Top")
		(7 "B.SilkS" user "Ref Des/Silkscreen Bottom")
		(1 "F.Mask" user "Board Geometry/Soldermask Top")
		(3 "B.Mask" user "Board Geometry/Soldermask Bottom")
		(17 "Dwgs.User" user "User.Drawings")
		(19 "Cmts.User" user "User.Comments")
		(21 "Eco1.User" user "User.Eco1")
		(23 "Eco2.User" user "User.Eco2")
		(25 "Edge.Cuts" user "Board Geometry/Outline")
		(27 "Margin" user)
		(31 "F.CrtYd" user "Package Geometry/Place Bound Top")
		(29 "B.CrtYd" user "Package Geometry/Place Bound Bottom")
		(35 "F.Fab" user "Ref Des/Assembly Top")
		(33 "B.Fab" user "Ref Des/Assembly Bottom")
	)
	(footprint ""
		(layer "B.Cu")
		(at 48.43653 -346.788994 90)
		(property "Reference" "PC449_2"
			(at 0 0 90)
			(layer "B.SilkS")
			(hide yes)
			(effects
				(font
					(size 1.27 1.27)
				)
				(justify mirror)
			)
		)
		(property "Value" ""
			(at 0 0 90)
			(layer "B.Fab")
			(effects
				(font
					(size 1.27 1.27)
				)
				(justify mirror)
			)
		)
		(duplicate_pad_numbers_are_jumpers no)
		(fp_line
			(start 1.524 -0.762)
			(end -1.524 -0.762)
			(stroke
				(width 0.1524)
				(type default)
			)
			(layer "B.SilkS")
		)
		(fp_line
			(start -1.524 -0.762)
			(end -1.524 0.762)
			(stroke
				(width 0.1524)
				(type default)
			)
			(layer "B.SilkS")
		)
		(fp_line
			(start 1.524 0.762)
			(end 1.524 -0.762)
			(stroke
				(width 0.1524)
				(type default)
			)
			(layer "B.SilkS")
		)
		(fp_line
			(start -1.524 0.762)
			(end 1.524 0.762)
			(stroke
				(width 0.1524)
				(type default)
			)
			(layer "B.SilkS")
		)
		(fp_line
			(start 1.1049 -0.724916)
			(end 1.1049 0.724916)
			(stroke
				(width 0.1)
				(type default)
			)
			(layer "B.Fab")
		)
		(fp_line
			(start -1.1049 -0.724916)
			(end 1.1049 -0.724916)
			(stroke
				(width 0.1)
				(type default)
			)
			(layer "B.Fab")
		)
		(fp_line
			(start 1.1049 0.724916)
			(end -1.1049 0.724916)
			(stroke
				(width 0.1)
				(type default)
			)
			(layer "B.Fab")
		)
		(fp_line
			(start -1.1049 0.724916)
			(end -1.1049 -0.724916)
			(stroke
				(width 0.1)
				(type default)
			)
			(layer "B.Fab")
		)
		(pad "1" smd rect
			(at 0.889 0 90)
			(size 1.016 1.27)
			(layers "B.Cu" "B.Mask" "B.Paste")
			(net "SW_P12V_AUX_PVDDIO_P1_FLT")
		)
		(pad "2" smd rect
			(at -0.889 0 90)
			(size 1.016 1.27)
			(layers "B.Cu" "B.Mask" "B.Paste")
			(net "GND")
		)
	)
	(footprint ""
		(layer "B.Cu")
		(at 314.965588 7.622794 180)
		(property "Reference" "J114"
			(at 4.525264 -1.200404 270)
			(unlocked yes)
			(layer "B.SilkS")
			(effects
				(font
					(size 0.7874 0.5842)
					(thickness 0.1524)
				)
				(justify left mirror)
			)
		)
		(property "Value" ""
			(at 0 0 0)
			(layer "B.Fab")
			(effects
				(font
					(size 1.27 1.27)
				)
				(justify mirror)
			)
		)
		(duplicate_pad_numbers_are_jumpers no)
		(fp_line
			(start 1.2192 2.06756)
			(end 1.2192 -2.06756)
			(stroke
				(width 0.1524)
				(type default)
			)
			(layer "B.SilkS")
		)
		(fp_line
			(start 1.2192 -2.06756)
			(end -1.2192 -2.06756)
			(stroke
				(width 0.1524)
				(type default)
			)
			(layer "B.SilkS")
		)
		(fp_line
			(start -1.2192 2.06756)
			(end 1.2192 2.06756)
			(stroke
				(width 0.1524)
				(type default)
			)
			(layer "B.SilkS")
		)
		(fp_line
			(start -1.2192 -2.06756)
			(end -1.2192 2.06756)
			(stroke
				(width 0.1524)
				(type default)
			)
			(layer "B.SilkS")
		)
		(pad "" np_thru_hole circle
			(at -3.4671 -1.27 90)
			(size 1.0414 1.0414)
			(drill 1.0414)
			(layers "*.Cu" "*.Mask")
			(clearance 0.381)
			(thermal_gap 0.381)
		)
		(pad "" np_thru_hole circle
			(at -3.4671 1.27 90)
			(size 1.0414 1.0414)
			(drill 1.0414)
			(layers "*.Cu" "*.Mask")
			(clearance 0.381)
			(thermal_gap 0.381)
		)
		(pad "" np_thru_hole circle
			(at 2.8829 -1.27 90)
			(size 1.0414 1.0414)
			(drill 1.0414)
			(layers "*.Cu" "*.Mask")
			(clearance 0.381)
			(thermal_gap 0.381)
		)
		(pad "" np_thru_hole circle
			(at 2.8829 1.27 90)
			(size 1.0414 1.0414)
			(drill 1.0414)
			(layers "*.Cu" "*.Mask")
			(clearance 0.381)
			(thermal_gap 0.381)
		)
		(pad "1" smd rect
			(at -0.8255 -0.249936 90)
			(size 0.3048 0.508)
			(layers "B.Cu" "B.Mask" "B.Paste")
			(net "DELTA_L_85_5INCH_IN5_DP")
		)
		(pad "2" smd rect
			(at -0.8255 0.249936 90)
			(size 0.3048 0.508)
			(layers "B.Cu" "B.Mask" "B.Paste")
			(net "DELTA_L_85_5INCH_IN5_DN")
		)
		(pad "3" smd circle
			(at 0 0)
			(size 0 0)
			(layers "B.Cu" "B.Mask" "B.Paste")
			(net "DELTA_L_GND_1")
		)
		(zone
			(layers "F.Cu" "B.Cu" "In1.Cu" "In2.Cu" "In3.Cu" "In4.Cu" "In5.Cu" "In6.Cu"
				"In7.Cu" "In8.Cu" "In9.Cu" "In10.Cu" "In11.Cu" "In12.Cu" "In13.Cu" "In14.Cu"
				"In15.Cu" "In16.Cu"
			)
			(hatch none 0.5)
			(connect_pads
				(clearance 0)
			)
			(min_thickness 0.25)
			(keepout
				(tracks not_allowed)
				(vias allowed)
				(pads allowed)
				(copperpour not_allowed)
				(footprints allowed)
			)
			(placement
				(enabled no)
				(sheetname "")
			)
			(fill
				(thermal_gap 0.5)
				(thermal_bridge_width 0.5)
				(island_removal_mode 0)
			)
			(polygon
				(pts
					(arc
						(start 313.009788 6.352794)
						(mid 311.155588 6.352794)
						(end 313.009788 6.352794)
					)
				)
			)
		)
		(zone
			(layers "F.Cu" "B.Cu" "In1.Cu" "In2.Cu" "In3.Cu" "In4.Cu" "In5.Cu" "In6.Cu"
				"In7.Cu" "In8.Cu" "In9.Cu" "In10.Cu" "In11.Cu" "In12.Cu" "In13.Cu" "In14.Cu"
				"In15.Cu" "In16.Cu"
			)
			(hatch none 0.5)
			(connect_pads
				(clearance 0)
			)
			(min_thickness 0.25)
			(keepout
				(tracks not_allowed)
				(vias allowed)
				(pads allowed)
				(copperpour not_allowed)
				(footprints allowed)
			)
			(placement
				(enabled no)
				(sheetname "")
			)
			(fill
				(thermal_gap 0.5)
				(thermal_bridge_width 0.5)
				(island_removal_mode 0)
			)
			(polygon
				(pts
					(arc
						(start 313.009788 8.892794)
						(mid 311.155588 8.892794)
						(end 313.009788 8.892794)
					)
				)
			)
		)
		(zone
			(layers "F.Cu" "B.Cu" "In1.Cu" "In2.Cu" "In3.Cu" "In4.Cu" "In5.Cu" "In6.Cu"
				"In7.Cu" "In8.Cu" "In9.Cu" "In10.Cu" "In11.Cu" "In12.Cu" "In13.Cu" "In14.Cu"
				"In15.Cu" "In16.Cu"
			)
			(hatch none 0.5)
			(connect_pads
				(clearance 0)
			)
			(min_thickness 0.25)
			(keepout
				(tracks not_allowed)
				(vias allowed)
				(pads allowed)
				(copperpour not_allowed)
				(footprints allowed)
			)
			(placement
				(enabled no)
				(sheetname "")
			)
			(fill
				(thermal_gap 0.5)
				(thermal_bridge_width 0.5)
				(island_removal_mode 0)
			)
			(polygon
				(pts
					(arc
						(start 319.359788 6.352794)
						(mid 317.505588 6.352794)
						(end 319.359788 6.352794)
					)
				)
			)
		)
		(zone
			(layers "F.Cu" "B.Cu" "In1.Cu" "In2.Cu" "In3.Cu" "In4.Cu" "In5.Cu" "In6.Cu"
				"In7.Cu" "In8.Cu" "In9.Cu" "In10.Cu" "In11.Cu" "In12.Cu" "In13.Cu" "In14.Cu"
				"In15.Cu" "In16.Cu"
			)
			(hatch none 0.5)
			(connect_pads
				(clearance 0)
			)
			(min_thickness 0.25)
			(keepout
				(tracks not_allowed)
				(vias allowed)
				(pads allowed)
				(copperpour not_allowed)
				(footprints allowed)
			)
			(placement
				(enabled no)
				(sheetname "")
			)
			(fill
				(thermal_gap 0.5)
				(thermal_bridge_width 0.5)
				(island_removal_mode 0)
			)
			(polygon
				(pts
					(arc
						(start 319.359788 8.892794)
						(mid 317.505588 8.892794)
						(end 319.359788 8.892794)
					)
				)
			)
		)
		(zone
			(layer "B.Cu")
			(hatch none 0.5)
			(connect_pads
				(clearance 0)
			)
			(min_thickness 0.25)
			(keepout
				(tracks not_allowed)
				(vias allowed)
				(pads allowed)
				(copperpour not_allowed)
				(footprints allowed)
			)
			(placement
				(enabled no)
				(sheetname "")
			)
			(fill
				(thermal_gap 0.5)
				(thermal_bridge_width 0.5)
				(island_removal_mode 0)
			)
			(polygon
				(pts
					(xy 316.083188 8.171434) (xy 316.083188 8.07593) (xy 315.486288 8.07593) (xy 315.486288 7.66953)
					(xy 316.083188 7.66953) (xy 316.083188 7.576058) (xy 315.486288 7.576058) (xy 315.486288 7.169658)
					(xy 316.083188 7.169658) (xy 316.083188 7.074154) (xy 315.384688 7.074154) (xy 315.384688 8.171434)
				)
			)
		)
	)
	(footprint ""
		(layer "B.Cu")
		(at 47.518574 -388.011162 -90)
		(property "Reference" "C282"
			(at 0 0 90)
			(layer "B.SilkS")
			(hide yes)
			(effects
				(font
					(size 1.27 1.27)
				)
				(justify mirror)
			)
		)
		(property "Value" ""
			(at 0 0 90)
			(layer "B.Fab")
			(effects
				(font
					(size 1.27 1.27)
				)
				(justify mirror)
			)
		)
		(duplicate_pad_numbers_are_jumpers no)
		(fp_line
			(start -0.299974 0.150114)
			(end 0.299974 0.150114)
			(stroke
				(width 0.1)
				(type default)
			)
			(layer "B.Fab")
		)
		(fp_line
			(start 0.299974 0.150114)
			(end 0.299974 -0.150114)
			(stroke
				(width 0.1)
				(type default)
			)
			(layer "B.Fab")
		)
		(fp_line
			(start -0.299974 -0.150114)
			(end -0.299974 0.150114)
			(stroke
				(width 0.1)
				(type default)
			)
			(layer "B.Fab")
		)
		(fp_line
			(start 0.299974 -0.150114)
			(end -0.299974 -0.150114)
			(stroke
				(width 0.1)
				(type default)
			)
			(layer "B.Fab")
		)
		(pad "1" smd rect
			(at 0.2667 0 90)
			(size 0.3048 0.381)
			(layers "B.Cu" "B.Mask" "B.Paste")
			(net "P0V9_CPU1_RT0_2A")
		)
		(pad "2" smd rect
			(at -0.2667 0 90)
			(size 0.3048 0.381)
			(layers "B.Cu" "B.Mask" "B.Paste")
			(net "GND")
		)
	)
	(footprint ""
		(layer "B.Cu")
		(at 162.46983 -17.79016 180)
		(property "Reference" "R4149"
			(at 0 0 0)
			(layer "B.SilkS")
			(hide yes)
			(effects
				(font
					(size 1.27 1.27)
				)
				(justify mirror)
			)
		)
		(property "Value" ""
			(at 0 0 0)
			(layer "B.Fab")
			(effects
				(font
					(size 1.27 1.27)
				)
				(justify mirror)
			)
		)
		(duplicate_pad_numbers_are_jumpers no)
		(fp_line
			(start 0.7874 0.4064)
			(end 0.7874 -0.4064)
			(stroke
				(width 0.1524)
				(type default)
			)
			(layer "B.SilkS")
		)
		(fp_line
			(start 0.7874 -0.4064)
			(end -0.7874 -0.4064)
			(stroke
				(width 0.1524)
				(type default)
			)
			(layer "B.SilkS")
		)
		(fp_line
			(start -0.7874 0.4064)
			(end 0.7874 0.4064)
			(stroke
				(width 0.1524)
				(type default)
			)
			(layer "B.SilkS")
		)
		(fp_line
			(start -0.7874 -0.4064)
			(end -0.7874 0.4064)
			(stroke
				(width 0.1524)
				(type default)
			)
			(layer "B.SilkS")
		)
		(fp_line
			(start 0.67945 0.3048)
			(end 0.67945 -0.305054)
			(stroke
				(width 0.1)
				(type default)
			)
			(layer "B.Fab")
		)
		(fp_line
			(start 0.67945 -0.305054)
			(end 0.12065 -0.305054)
			(stroke
				(width 0.1)
				(type default)
			)
			(layer "B.Fab")
		)
		(fp_line
			(start 0.12065 0.3048)
			(end 0.67945 0.3048)
			(stroke
				(width 0.1)
				(type default)
			)
			(layer "B.Fab")
		)
		(fp_line
			(start 0.12065 0.2794)
			(end 0.12065 0.3048)
			(stroke
				(width 0.1)
				(type default)
			)
			(layer "B.Fab")
		)
		(fp_line
			(start 0.12065 -0.2794)
			(end -0.12065 -0.2794)
			(stroke
				(width 0.1)
				(type default)
			)
			(layer "B.Fab")
		)
		(fp_line
			(start 0.12065 -0.305054)
			(end 0.12065 -0.2794)
			(stroke
				(width 0.1)
				(type default)
			)
			(layer "B.Fab")
		)
		(fp_line
			(start -0.120396 0.3048)
			(end -0.120396 0.2794)
			(stroke
				(width 0.1)
				(type default)
			)
			(layer "B.Fab")
		)
		(fp_line
			(start -0.120396 0.2794)
			(end 0.12065 0.2794)
			(stroke
				(width 0.1)
				(type default)
			)
			(layer "B.Fab")
		)
		(fp_line
			(start -0.12065 -0.2794)
			(end -0.12065 -0.3048)
			(stroke
				(width 0.1)
				(type default)
			)
			(layer "B.Fab")
		)
		(fp_line
			(start -0.12065 -0.3048)
			(end -0.67945 -0.3048)
			(stroke
				(width 0.1)
				(type default)
			)
			(layer "B.Fab")
		)
		(fp_line
			(start -0.67945 0.3048)
			(end -0.120396 0.3048)
			(stroke
				(width 0.1)
				(type default)
			)
			(layer "B.Fab")
		)
		(fp_line
			(start -0.67945 -0.3048)
			(end -0.67945 0.3048)
			(stroke
				(width 0.1)
				(type default)
			)
			(layer "B.Fab")
		)
		(pad "1" smd circle
			(at 0.40005 0)
			(size 0 0)
			(layers "B.Cu" "B.Mask" "B.Paste")
			(net "SMB_1_PLD_3V3AUX_SCL")
		)
		(pad "2" smd circle
			(at -0.40005 0)
			(size 0 0)
			(layers "B.Cu" "B.Mask" "B.Paste")
			(net "SMB_1_PLD_3V3AUX_SCL_R1")
		)
	)
	(footprint ""
		(layer "B.Cu")
		(at 352.501454 -266.00531)
		(property "Reference" "C3933"
			(at 0 0 0)
			(layer "B.SilkS")
			(hide yes)
			(effects
				(font
					(size 1.27 1.27)
				)
				(justify mirror)
			)
		)
		(property "Value" ""
			(at 0 0 0)
			(layer "B.Fab")
			(effects
				(font
					(size 1.27 1.27)
				)
				(justify mirror)
			)
		)
		(duplicate_pad_numbers_are_jumpers no)
		(fp_line
			(start -0.7874 -0.4064)
			(end -0.7874 0.4064)
			(stroke
				(width 0.1524)
				(type default)
			)
			(layer "B.SilkS")
		)
		(fp_line
			(start -0.7874 0.4064)
			(end 0.7874 0.4064)
			(stroke
				(width 0.1524)
				(type default)
			)
			(layer "B.SilkS")
		)
		(fp_line
			(start 0.7874 -0.4064)
			(end -0.7874 -0.4064)
			(stroke
				(width 0.1524)
				(type default)
			)
			(layer "B.SilkS")
		)
		(fp_line
			(start 0.7874 0.4064)
			(end 0.7874 -0.4064)
			(stroke
				(width 0.1524)
				(type default)
			)
			(layer "B.SilkS")
		)
		(fp_line
			(start -0.67945 -0.3048)
			(end -0.67945 0.3048)
			(stroke
				(width 0.1)
				(type default)
			)
			(layer "B.Fab")
		)
		(fp_line
			(start -0.67945 0.3048)
			(end -0.120396 0.3048)
			(stroke
				(width 0.1)
				(type default)
			)
			(layer "B.Fab")
		)
		(fp_line
			(start -0.12065 -0.3048)
			(end -0.67945 -0.3048)
			(stroke
				(width 0.1)
				(type default)
			)
			(layer "B.Fab")
		)
		(fp_line
			(start -0.12065 -0.2794)
			(end -0.12065 -0.3048)
			(stroke
				(width 0.1)
				(type default)
			)
			(layer "B.Fab")
		)
		(fp_line
			(start -0.120396 0.2794)
			(end 0.12065 0.2794)
			(stroke
				(width 0.1)
				(type default)
			)
			(layer "B.Fab")
		)
		(fp_line
			(start -0.120396 0.3048)
			(end -0.120396 0.2794)
			(stroke
				(width 0.1)
				(type default)
			)
			(layer "B.Fab")
		)
		(fp_line
			(start 0.12065 -0.305054)
			(end 0.12065 -0.2794)
			(stroke
				(width 0.1)
				(type default)
			)
			(layer "B.Fab")
		)
		(fp_line
			(start 0.12065 -0.2794)
			(end -0.12065 -0.2794)
			(stroke
				(width 0.1)
				(type default)
			)
			(layer "B.Fab")
		)
		(fp_line
			(start 0.12065 0.2794)
			(end 0.12065 0.3048)
			(stroke
				(width 0.1)
				(type default)
			)
			(layer "B.Fab")
		)
		(fp_line
			(start 0.12065 0.3048)
			(end 0.67945 0.3048)
			(stroke
				(width 0.1)
				(type default)
			)
			(layer "B.Fab")
		)
		(fp_line
			(start 0.67945 -0.305054)
			(end 0.12065 -0.305054)
			(stroke
				(width 0.1)
				(type default)
			)
			(layer "B.Fab")
		)
		(fp_line
			(start 0.67945 0.3048)
			(end 0.67945 -0.305054)
			(stroke
				(width 0.1)
				(type default)
			)
			(layer "B.Fab")
		)
		(pad "1" smd circle
			(at 0.40005 0 180)
			(size 0 0)
			(layers "B.Cu" "B.Mask" "B.Paste")
			(net "PVDD11_S3_P0")
		)
		(pad "2" smd circle
			(at -0.40005 0 180)
			(size 0 0)
			(layers "B.Cu" "B.Mask" "B.Paste")
			(net "GND")
		)
	)
	(footprint ""
		(layer "B.Cu")
		(at 243.816378 -315.95568 -90)
		(property "Reference" "PC6508"
			(at 0 0 90)
			(layer "B.SilkS")
			(hide yes)
			(effects
				(font
					(size 1.27 1.27)
				)
				(justify mirror)
			)
		)
		(property "Value" ""
			(at 0 0 90)
			(layer "B.Fab")
			(effects
				(font
					(size 1.27 1.27)
				)
				(justify mirror)
			)
		)
		(duplicate_pad_numbers_are_jumpers no)
		(fp_line
			(start -1.524 0.762)
			(end 1.524 0.762)
			(stroke
				(width 0.1524)
				(type default)
			)
			(layer "B.SilkS")
		)
		(fp_line
			(start 1.524 0.762)
			(end 1.524 -0.762)
			(stroke
				(width 0.1524)
				(type default)
			)
			(layer "B.SilkS")
		)
		(fp_line
			(start -1.524 -0.762)
			(end -1.524 0.762)
			(stroke
				(width 0.1524)
				(type default)
			)
			(layer "B.SilkS")
		)
		(fp_line
			(start 1.524 -0.762)
			(end -1.524 -0.762)
			(stroke
				(width 0.1524)
				(type default)
			)
			(layer "B.SilkS")
		)
		(fp_line
			(start -1.1049 0.724916)
			(end -1.1049 -0.724916)
			(stroke
				(width 0.1)
				(type default)
			)
			(layer "B.Fab")
		)
		(fp_line
			(start 1.1049 0.724916)
			(end -1.1049 0.724916)
			(stroke
				(width 0.1)
				(type default)
			)
			(layer "B.Fab")
		)
		(fp_line
			(start -1.1049 -0.724916)
			(end 1.1049 -0.724916)
			(stroke
				(width 0.1)
				(type default)
			)
			(layer "B.Fab")
		)
		(fp_line
			(start 1.1049 -0.724916)
			(end 1.1049 0.724916)
			(stroke
				(width 0.1)
				(type default)
			)
			(layer "B.Fab")
		)
		(pad "1" smd rect
			(at 0.889 0 270)
			(size 1.016 1.27)
			(layers "B.Cu" "B.Mask" "B.Paste")
			(net "P1V8_CPU0_RT_1D")
		)
		(pad "2" smd rect
			(at -0.889 0 270)
			(size 1.016 1.27)
			(layers "B.Cu" "B.Mask" "B.Paste")
			(net "GND")
		)
	)
)
